# SCM (Grand Teton) — schematic netlist excerpt (pin names and nets, part order shuffled) for the footprints in the layout excerpt that follows; sources: Cadence DE-HDL packaged netlist, KiCad conversion of 12092022_DA0F0TMDCD0_F0T_Management_Board_D_brd_V3_OCP.brd

H6  HOLE  EMPTY  pkg TH  page 57 : \1\ = GND
C234  Q_CAP  22UF 10V 20% EMPTY  pkg C0603  page 21 : A = P3V3_AUX ; B = GND
R762  Q_RES  33.2 1% CHIP  pkg 0402LF  page 12 : A = UART_6_BMC_RXD ; B = UART_6_BMC_R_RXD

(kicad_pcb
	(version 20260206)
	(generator "pcbnew")
	(generator_version "10.0")
	(general
		(thickness 1.6)
		(legacy_teardrops no)
	)
	(paper "A4")
	(title_block
		(title "12092022_DA0F0TMDCD0_F0T_Management_Board_D_brd_V3_OCP.brd")
		(comment 1 "Grand Teton / footprints 549-551 of 1440")
	)
	(layers
		(0 "F.Cu" signal "TOP")
		(4 "In1.Cu" signal "GND")
		(6 "In2.Cu" signal "IN1")
		(8 "In3.Cu" signal "GND1")
		(10 "In4.Cu" signal "IN2")
		(12 "In5.Cu" signal "VCC")
		(14 "In6.Cu" signal "VCC1")
		(16 "In7.Cu" signal "IN3")
		(18 "In8.Cu" signal "GND2")
		(20 "In9.Cu" signal "IN4")
		(22 "In10.Cu" signal "GND3")
		(2 "B.Cu" signal "BOTTOM")
		(9 "F.Adhes" user "F.Adhesive")
		(11 "B.Adhes" user "B.Adhesive")
		(13 "F.Paste" user "Package Geometry/Pastemask Top")
		(15 "B.Paste" user "Package Geometry/Pastemask Bottom")
		(5 "F.SilkS" user "Ref Des/Silkscreen Top")
		(7 "B.SilkS" user "Ref Des/Silkscreen Bottom")
		(1 "F.Mask" user "Board Geometry/Soldermask Top")
		(3 "B.Mask" user "Board Geometry/Soldermask Bottom")
		(17 "Dwgs.User" user "User.Drawings")
		(19 "Cmts.User" user "User.Comments")
		(21 "Eco1.User" user "User.Eco1")
		(23 "Eco2.User" user "User.Eco2")
		(25 "Edge.Cuts" user "Board Geometry/Outline")
		(27 "Margin" user)
		(31 "F.CrtYd" user "Package Geometry/Place Bound Top")
		(29 "B.CrtYd" user "Package Geometry/Place Bound Bottom")
		(35 "F.Fab" user "Ref Des/Assembly Top")
		(33 "B.Fab" user "Ref Des/Assembly Bottom")
	)
	(footprint ""
		(layer "F.Cu")
		(at 17.7165 -69.596 -90)
		(property "Reference" "C234"
			(at 0 0 270)
			(layer "F.SilkS")
			(hide yes)
			(effects
				(font
					(size 1.27 1.27)
				)
			)
		)
		(property "Value" ""
			(at 0 0 270)
			(layer "F.Fab")
			(effects
				(font
					(size 1.27 1.27)
				)
			)
		)
		(duplicate_pad_numbers_are_jumpers no)
		(fp_line
			(start -1.2954 0.5842)
			(end -1.2954 -0.5842)
			(stroke
				(width 0.1524)
				(type default)
			)
			(layer "F.SilkS")
		)
		(fp_line
			(start 1.2954 0.5842)
			(end -1.2954 0.5842)
			(stroke
				(width 0.1524)
				(type default)
			)
			(layer "F.SilkS")
		)
		(fp_line
			(start -1.2954 -0.5842)
			(end 1.2954 -0.5842)
			(stroke
				(width 0.1524)
				(type default)
			)
			(layer "F.SilkS")
		)
		(fp_line
			(start 0 -0.5842)
			(end 0 0.5842)
			(stroke
				(width 0.1524)
				(type default)
			)
			(layer "F.SilkS")
		)
		(fp_line
			(start 1.2954 -0.5842)
			(end 1.2954 0.5842)
			(stroke
				(width 0.1524)
				(type default)
			)
			(layer "F.SilkS")
		)
		(fp_line
			(start -0.8636 0.4572)
			(end -0.8636 0.4064)
			(stroke
				(width 0.1)
				(type default)
			)
			(layer "F.Fab")
		)
		(fp_line
			(start 0.8636 0.4572)
			(end -0.8636 0.4572)
			(stroke
				(width 0.1)
				(type default)
			)
			(layer "F.Fab")
		)
		(fp_line
			(start -1.1938 0.4064)
			(end -1.1938 -0.4064)
			(stroke
				(width 0.1)
				(type default)
			)
			(layer "F.Fab")
		)
		(fp_line
			(start -0.8636 0.4064)
			(end -1.1938 0.4064)
			(stroke
				(width 0.1)
				(type default)
			)
			(layer "F.Fab")
		)
		(fp_line
			(start 0.8636 0.4064)
			(end 0.8636 0.4572)
			(stroke
				(width 0.1)
				(type default)
			)
			(layer "F.Fab")
		)
		(fp_line
			(start 1.1938 0.4064)
			(end 0.8636 0.4064)
			(stroke
				(width 0.1)
				(type default)
			)
			(layer "F.Fab")
		)
		(fp_line
			(start -1.1938 -0.4064)
			(end -0.8636 -0.4064)
			(stroke
				(width 0.1)
				(type default)
			)
			(layer "F.Fab")
		)
		(fp_line
			(start -0.8636 -0.4064)
			(end -0.8636 -0.4572)
			(stroke
				(width 0.1)
				(type default)
			)
			(layer "F.Fab")
		)
		(fp_line
			(start 0.8636 -0.4064)
			(end 1.1938 -0.4064)
			(stroke
				(width 0.1)
				(type default)
			)
			(layer "F.Fab")
		)
		(fp_line
			(start 1.1938 -0.4064)
			(end 1.1938 0.4064)
			(stroke
				(width 0.1)
				(type default)
			)
			(layer "F.Fab")
		)
		(fp_line
			(start -0.8636 -0.4572)
			(end 0.8636 -0.4572)
			(stroke
				(width 0.1)
				(type default)
			)
			(layer "F.Fab")
		)
		(fp_line
			(start 0.8636 -0.4572)
			(end 0.8636 -0.4064)
			(stroke
				(width 0.1)
				(type default)
			)
			(layer "F.Fab")
		)
		(pad "1" smd rect
			(at -0.7366 0 180)
			(size 0.7112 0.8128)
			(layers "F.Cu" "F.Mask" "F.Paste")
			(net "P3V3_AUX")
		)
		(pad "2" smd rect
			(at 0.7366 0 180)
			(size 0.7112 0.8128)
			(layers "F.Cu" "F.Mask" "F.Paste")
			(net "GND")
		)
	)
	(footprint ""
		(layer "F.Cu")
		(at 5.599938 -11.789918)
		(property "Reference" "H6"
			(at -4.964938 0.005588 0)
			(unlocked yes)
			(layer "F.SilkS")
			(effects
				(font
					(size 0.7874 0.5842)
					(thickness 0.1524)
				)
				(justify left)
			)
		)
		(property "Value" ""
			(at 0 0 0)
			(layer "F.Fab")
			(effects
				(font
					(size 1.27 1.27)
				)
			)
		)
		(duplicate_pad_numbers_are_jumpers no)
		(pad "1" thru_hole circle
			(at 0 0)
			(size 6.5024 6.5024)
			(drill 3.2004)
			(layers "*.Cu" "*.Mask")
			(remove_unused_layers no)
			(net "GND")
			(clearance -1.397)
		)
	)
	(footprint ""
		(layer "F.Cu")
		(at 44.704 -34.6202 90)
		(property "Reference" "R762"
			(at 0 0 90)
			(layer "F.SilkS")
			(hide yes)
			(effects
				(font
					(size 1.27 1.27)
				)
			)
		)
		(property "Value" ""
			(at 0 0 90)
			(layer "F.Fab")
			(effects
				(font
					(size 1.27 1.27)
				)
			)
		)
		(duplicate_pad_numbers_are_jumpers no)
		(fp_line
			(start 0.7874 -0.4064)
			(end 0.7874 0.4064)
			(stroke
				(width 0.1524)
				(type default)
			)
			(layer "F.SilkS")
		)
		(fp_line
			(start -0.7874 -0.4064)
			(end 0.7874 -0.4064)
			(stroke
				(width 0.1524)
				(type default)
			)
			(layer "F.SilkS")
		)
		(fp_line
			(start 0.7874 0.4064)
			(end -0.7874 0.4064)
			(stroke
				(width 0.1524)
				(type default)
			)
			(layer "F.SilkS")
		)
		(fp_line
			(start -0.7874 0.4064)
			(end -0.7874 -0.4064)
			(stroke
				(width 0.1524)
				(type default)
			)
			(layer "F.SilkS")
		)
		(fp_line
			(start -0.12065 -0.305054)
			(end -0.12065 -0.2794)
			(stroke
				(width 0.1)
				(type default)
			)
			(layer "F.Fab")
		)
		(fp_line
			(start -0.67945 -0.305054)
			(end -0.12065 -0.305054)
			(stroke
				(width 0.1)
				(type default)
			)
			(layer "F.Fab")
		)
		(fp_line
			(start 0.67945 -0.3048)
			(end 0.67945 0.3048)
			(stroke
				(width 0.1)
				(type default)
			)
			(layer "F.Fab")
		)
		(fp_line
			(start 0.12065 -0.3048)
			(end 0.67945 -0.3048)
			(stroke
				(width 0.1)
				(type default)
			)
			(layer "F.Fab")
		)
		(fp_line
			(start 0.12065 -0.2794)
			(end 0.12065 -0.3048)
			(stroke
				(width 0.1)
				(type default)
			)
			(layer "F.Fab")
		)
		(fp_line
			(start -0.12065 -0.2794)
			(end 0.12065 -0.2794)
			(stroke
				(width 0.1)
				(type default)
			)
			(layer "F.Fab")
		)
		(fp_line
			(start 0.120396 0.2794)
			(end -0.12065 0.2794)
			(stroke
				(width 0.1)
				(type default)
			)
			(layer "F.Fab")
		)
		(fp_line
			(start -0.12065 0.2794)
			(end -0.12065 0.3048)
			(stroke
				(width 0.1)
				(type default)
			)
			(layer "F.Fab")
		)
		(fp_line
			(start 0.67945 0.3048)
			(end 0.120396 0.3048)
			(stroke
				(width 0.1)
				(type default)
			)
			(layer "F.Fab")
		)
		(fp_line
			(start 0.120396 0.3048)
			(end 0.120396 0.2794)
			(stroke
				(width 0.1)
				(type default)
			)
			(layer "F.Fab")
		)
		(fp_line
			(start -0.12065 0.3048)
			(end -0.67945 0.3048)
			(stroke
				(width 0.1)
				(type default)
			)
			(layer "F.Fab")
		)
		(fp_line
			(start -0.67945 0.3048)
			(end -0.67945 -0.305054)
			(stroke
				(width 0.1)
				(type default)
			)
			(layer "F.Fab")
		)
		(pad "1" smd circle
			(at -0.40005 0 90)
			(size 0 0)
			(layers "F.Cu" "F.Mask" "F.Paste")
			(net "UART_6_BMC_RXD")
		)
		(pad "2" smd circle
			(at 0.40005 0 90)
			(size 0 0)
			(layers "F.Cu" "F.Mask" "F.Paste")
			(net "UART_6_BMC_R_RXD")
		)
	)
)
